(kicad_pcb
	(version 20260206)
	(generator "pcbnew")
	(generator_version "10.0")
	(general
		(thickness 1.6)
		(legacy_teardrops no)
	)
	(paper "A4")
	(title_block
		(title "Bryce Canyon_IOM_M2_16342-2_OCP.brd")
		(comment 1 "Bryce Canyon / footprints 1091-1097 of 1146")
	)
	(layers
		(0 "F.Cu" signal "TOP")
		(4 "In1.Cu" signal "L2GND")
		(6 "In2.Cu" signal "L3")
		(8 "In3.Cu" signal "L4VCC")
		(10 "In4.Cu" signal "L5VCC")
		(12 "In5.Cu" signal "L6")
		(14 "In6.Cu" signal "L7GND")
		(2 "B.Cu" signal "BOTTOM")
		(9 "F.Adhes" user "F.Adhesive")
		(11 "B.Adhes" user "B.Adhesive")
		(13 "F.Paste" user "Package Geometry/Pastemask Top")
		(15 "B.Paste" user "Package Geometry/Pastemask Bottom")
		(5 "F.SilkS" user "Ref Des/Silkscreen Top")
		(7 "B.SilkS" user "Ref Des/Silkscreen Bottom")
		(1 "F.Mask" user "Board Geometry/Soldermask Top")
		(3 "B.Mask" user "Board Geometry/Soldermask Bottom")
		(17 "Dwgs.User" user "User.Drawings")
		(19 "Cmts.User" user "User.Comments")
		(21 "Eco1.User" user "User.Eco1")
		(23 "Eco2.User" user "User.Eco2")
		(25 "Edge.Cuts" user "Board Geometry/Outline")
		(27 "Margin" user)
		(31 "F.CrtYd" user "Package Geometry/Place Bound Top")
		(29 "B.CrtYd" user "Package Geometry/Place Bound Bottom")
		(35 "F.Fab" user "Ref Des/Assembly Top")
		(33 "B.Fab" user "Ref Des/Assembly Bottom")
	)
	(footprint ""
		(layer "B.Cu")
		(at 50.75682 -148.19376 -90)
		(property "Reference" "C101"
			(at 0 0 90)
			(layer "B.SilkS")
			(hide yes)
			(effects
				(font
					(size 1.27 1.27)
				)
				(justify mirror)
			)
		)
		(property "Value" "SC1U16V3KX-5GP"
			(at 0 -2.8194 270)
			(unlocked yes)
			(layer "B.Fab")
			(hide yes)
			(effects
				(font
					(size 1.016 1.016)
					(thickness 0.1524)
				)
				(justify mirror)
			)
		)
		(property "Device Type" "C603H36"
			(at 0 -4.3434 270)
			(unlocked yes)
			(layer "B.Fab")
			(hide yes)
			(effects
				(font
					(size 1.016 1.016)
					(thickness 0.1524)
				)
				(justify mirror)
			)
		)
		(duplicate_pad_numbers_are_jumpers no)
		(fp_line
			(start -0.508 0)
			(end 0.508 0)
			(stroke
				(width 0.2032)
				(type default)
			)
			(layer "B.SilkS")
		)
		(fp_rect
			(start 0.5842 1.3335)
			(end -0.5842 -1.3335)
			(stroke
				(width 0)
				(type default)
			)
			(fill no)
			(layer "B.CrtYd")
		)
		(fp_rect
			(start 0.5842 1.3335)
			(end -0.5842 -1.3335)
			(stroke
				(width 0)
				(type default)
			)
			(fill no)
			(layer "B.Fab")
		)
		(pad "1" smd custom
			(at 0 -0.762 90)
			(size 0.2159 0.2159)
			(layers "B.Cu" "B.Mask" "B.Paste")
			(net "P3V3_STBY")
			(options
				(clearance outline)
				(anchor circle)
			)
			(primitives
				(gr_poly
					(pts
						(arc
							(start -0.3302 0.4318)
							(mid -0.402042 0.402042)
							(end -0.4318 0.3302)
						)
						(arc
							(start -0.4318 -0.3302)
							(mid -0.402042 -0.402042)
							(end -0.3302 -0.4318)
						)
						(arc
							(start 0.3302 -0.4318)
							(mid 0.402042 -0.402042)
							(end 0.4318 -0.3302)
						)
						(arc
							(start 0.4318 0.3302)
							(mid 0.402042 0.402042)
							(end 0.3302 0.4318)
						)
					)
					(width 0)
					(fill yes)
				)
			)
		)
		(pad "2" smd custom
			(at 0 0.762 90)
			(size 0.2159 0.2159)
			(layers "B.Cu" "B.Mask" "B.Paste")
			(net "GND")
			(options
				(clearance outline)
				(anchor circle)
			)
			(primitives
				(gr_poly
					(pts
						(arc
							(start -0.3302 0.4318)
							(mid -0.402042 0.402042)
							(end -0.4318 0.3302)
						)
						(arc
							(start -0.4318 -0.3302)
							(mid -0.402042 -0.402042)
							(end -0.3302 -0.4318)
						)
						(arc
							(start 0.3302 -0.4318)
							(mid 0.402042 -0.402042)
							(end 0.4318 -0.3302)
						)
						(arc
							(start 0.4318 0.3302)
							(mid 0.402042 0.402042)
							(end 0.3302 0.4318)
						)
					)
					(width 0)
					(fill yes)
				)
			)
		)
	)
	(footprint ""
		(layer "B.Cu")
		(at 60.4774 -148.5138 180)
		(property "Reference" "R384"
			(at 0 0 0)
			(layer "B.SilkS")
			(hide yes)
			(effects
				(font
					(size 1.27 1.27)
				)
				(justify mirror)
			)
		)
		(property "Value" "4K7R2F-GP"
			(at -0.064008 -3.993896 180)
			(unlocked yes)
			(layer "B.Fab")
			(hide yes)
			(effects
				(font
					(size 1.016 1.016)
					(thickness 0.1524)
				)
				(justify mirror)
			)
		)
		(property "Device Type" "R402H16"
			(at -0.064008 -5.517896 180)
			(unlocked yes)
			(layer "B.Fab")
			(hide yes)
			(effects
				(font
					(size 1.016 1.016)
					(thickness 0.1524)
				)
				(justify mirror)
			)
		)
		(duplicate_pad_numbers_are_jumpers no)
		(fp_line
			(start 0.508 -0.9398)
			(end 0.508 0.9398)
			(stroke
				(width 0.1524)
				(type default)
			)
			(layer "B.SilkS")
		)
		(fp_line
			(start -0.508 -0.9398)
			(end 0.508 -0.9398)
			(stroke
				(width 0.1524)
				(type default)
			)
			(layer "B.SilkS")
		)
		(fp_rect
			(start 0.508 0.9398)
			(end -0.508 -0.9398)
			(stroke
				(width 0)
				(type default)
			)
			(fill no)
			(layer "B.CrtYd")
		)
		(fp_rect
			(start 0.508 0.9398)
			(end -0.508 -0.9398)
			(stroke
				(width 0)
				(type default)
			)
			(fill no)
			(layer "B.Fab")
		)
		(pad "1" smd custom
			(at 0 -0.4445)
			(size 0.1397 0.1397)
			(layers "B.Cu" "B.Mask" "B.Paste")
			(net "P3V3_STBY")
			(options
				(clearance outline)
				(anchor circle)
			)
			(primitives
				(gr_poly
					(pts
						(arc
							(start -0.1778 0.2794)
							(mid -0.249642 0.249642)
							(end -0.2794 0.1778)
						)
						(arc
							(start -0.2794 -0.1778)
							(mid -0.249642 -0.249642)
							(end -0.1778 -0.2794)
						)
						(arc
							(start 0.1778 -0.2794)
							(mid 0.249642 -0.249642)
							(end 0.2794 -0.1778)
						)
						(arc
							(start 0.2794 0.1778)
							(mid 0.249642 0.249642)
							(end 0.1778 0.2794)
						)
					)
					(width 0)
					(fill yes)
				)
			)
		)
		(pad "2" smd custom
			(at 0 0.4445)
			(size 0.1397 0.1397)
			(layers "B.Cu" "B.Mask" "B.Paste")
			(net "MAC1_TXD3")
			(options
				(clearance outline)
				(anchor circle)
			)
			(primitives
				(gr_poly
					(pts
						(arc
							(start -0.1778 0.2794)
							(mid -0.249642 0.249642)
							(end -0.2794 0.1778)
						)
						(arc
							(start -0.2794 -0.1778)
							(mid -0.249642 -0.249642)
							(end -0.1778 -0.2794)
						)
						(arc
							(start 0.1778 -0.2794)
							(mid 0.249642 -0.249642)
							(end 0.2794 -0.1778)
						)
						(arc
							(start 0.2794 0.1778)
							(mid 0.249642 0.249642)
							(end 0.1778 0.2794)
						)
					)
					(width 0)
					(fill yes)
				)
			)
		)
	)
	(footprint ""
		(layer "B.Cu")
		(at 90.805 -143.5608 180)
		(property "Reference" "R722"
			(at 0 0 0)
			(layer "B.SilkS")
			(hide yes)
			(effects
				(font
					(size 1.27 1.27)
				)
				(justify mirror)
			)
		)
		(property "Value" "10KR2J-3-GP"
			(at -0.064008 -3.993896 180)
			(unlocked yes)
			(layer "B.Fab")
			(hide yes)
			(effects
				(font
					(size 1.016 1.016)
					(thickness 0.1524)
				)
				(justify mirror)
			)
		)
		(property "Device Type" "R402H16"
			(at -0.064008 -5.517896 180)
			(unlocked yes)
			(layer "B.Fab")
			(hide yes)
			(effects
				(font
					(size 1.016 1.016)
					(thickness 0.1524)
				)
				(justify mirror)
			)
		)
		(duplicate_pad_numbers_are_jumpers no)
		(fp_line
			(start 0.508 -0.9398)
			(end 0.508 0.9398)
			(stroke
				(width 0.1524)
				(type default)
			)
			(layer "B.SilkS")
		)
		(fp_line
			(start -0.508 -0.9398)
			(end 0.508 -0.9398)
			(stroke
				(width 0.1524)
				(type default)
			)
			(layer "B.SilkS")
		)
		(fp_rect
			(start 0.508 0.9398)
			(end -0.508 -0.9398)
			(stroke
				(width 0)
				(type default)
			)
			(fill no)
			(layer "B.CrtYd")
		)
		(fp_rect
			(start 0.508 0.9398)
			(end -0.508 -0.9398)
			(stroke
				(width 0)
				(type default)
			)
			(fill no)
			(layer "B.Fab")
		)
		(pad "1" smd custom
			(at 0 -0.4445)
			(size 0.1397 0.1397)
			(layers "B.Cu" "B.Mask" "B.Paste")
			(net "DB_PRSNT_BMC_N")
			(options
				(clearance outline)
				(anchor circle)
			)
			(primitives
				(gr_poly
					(pts
						(arc
							(start -0.1778 0.2794)
							(mid -0.249642 0.249642)
							(end -0.2794 0.1778)
						)
						(arc
							(start -0.2794 -0.1778)
							(mid -0.249642 -0.249642)
							(end -0.1778 -0.2794)
						)
						(arc
							(start 0.1778 -0.2794)
							(mid 0.249642 -0.249642)
							(end 0.2794 -0.1778)
						)
						(arc
							(start 0.2794 0.1778)
							(mid 0.249642 0.249642)
							(end 0.1778 0.2794)
						)
					)
					(width 0)
					(fill yes)
				)
			)
		)
		(pad "2" smd custom
			(at 0 0.4445)
			(size 0.1397 0.1397)
			(layers "B.Cu" "B.Mask" "B.Paste")
			(net "P3V3_STBY")
			(options
				(clearance outline)
				(anchor circle)
			)
			(primitives
				(gr_poly
					(pts
						(arc
							(start -0.1778 0.2794)
							(mid -0.249642 0.249642)
							(end -0.2794 0.1778)
						)
						(arc
							(start -0.2794 -0.1778)
							(mid -0.249642 -0.249642)
							(end -0.1778 -0.2794)
						)
						(arc
							(start 0.1778 -0.2794)
							(mid 0.249642 -0.249642)
							(end 0.2794 -0.1778)
						)
						(arc
							(start 0.2794 0.1778)
							(mid 0.249642 0.249642)
							(end 0.1778 0.2794)
						)
					)
					(width 0)
					(fill yes)
				)
			)
		)
	)
	(footprint ""
		(layer "B.Cu")
		(at 177.303176 -121.968006 90)
		(property "Reference" "R815"
			(at 0 0 90)
			(layer "B.SilkS")
			(hide yes)
			(effects
				(font
					(size 1.27 1.27)
				)
				(justify mirror)
			)
		)
		(property "Value" "1KR2F-3-GP"
			(at -0.064008 -3.993896 90)
			(unlocked yes)
			(layer "B.Fab")
			(hide yes)
			(effects
				(font
					(size 1.016 1.016)
					(thickness 0.1524)
				)
				(justify mirror)
			)
		)
		(property "Device Type" "R402H16"
			(at -0.064008 -5.517896 90)
			(unlocked yes)
			(layer "B.Fab")
			(hide yes)
			(effects
				(font
					(size 1.016 1.016)
					(thickness 0.1524)
				)
				(justify mirror)
			)
		)
		(duplicate_pad_numbers_are_jumpers no)
		(fp_line
			(start 0.508 -0.9398)
			(end 0.508 0.9398)
			(stroke
				(width 0.1524)
				(type default)
			)
			(layer "B.SilkS")
		)
		(fp_line
			(start -0.508 -0.9398)
			(end 0.508 -0.9398)
			(stroke
				(width 0.1524)
				(type default)
			)
			(layer "B.SilkS")
		)
		(fp_rect
			(start 0.508 0.9398)
			(end -0.508 -0.9398)
			(stroke
				(width 0)
				(type default)
			)
			(fill no)
			(layer "B.CrtYd")
		)
		(fp_rect
			(start 0.508 0.9398)
			(end -0.508 -0.9398)
			(stroke
				(width 0)
				(type default)
			)
			(fill no)
			(layer "B.Fab")
		)
		(pad "1" smd custom
			(at 0 -0.4445 270)
			(size 0.1397 0.1397)
			(layers "B.Cu" "B.Mask" "B.Paste")
			(net "P1V8_STBY")
			(options
				(clearance outline)
				(anchor circle)
			)
			(primitives
				(gr_poly
					(pts
						(arc
							(start -0.1778 0.2794)
							(mid -0.249642 0.249642)
							(end -0.2794 0.1778)
						)
						(arc
							(start -0.2794 -0.1778)
							(mid -0.249642 -0.249642)
							(end -0.1778 -0.2794)
						)
						(arc
							(start 0.1778 -0.2794)
							(mid 0.249642 -0.249642)
							(end 0.2794 -0.1778)
						)
						(arc
							(start 0.2794 0.1778)
							(mid 0.249642 0.249642)
							(end 0.1778 0.2794)
						)
					)
					(width 0)
					(fill yes)
				)
			)
		)
		(pad "2" smd custom
			(at 0 0.4445 270)
			(size 0.1397 0.1397)
			(layers "B.Cu" "B.Mask" "B.Paste")
			(net "I2C_M2_2_1V8_SCL")
			(options
				(clearance outline)
				(anchor circle)
			)
			(primitives
				(gr_poly
					(pts
						(arc
							(start -0.1778 0.2794)
							(mid -0.249642 0.249642)
							(end -0.2794 0.1778)
						)
						(arc
							(start -0.2794 -0.1778)
							(mid -0.249642 -0.249642)
							(end -0.1778 -0.2794)
						)
						(arc
							(start 0.1778 -0.2794)
							(mid 0.249642 -0.249642)
							(end 0.2794 -0.1778)
						)
						(arc
							(start 0.2794 0.1778)
							(mid 0.249642 0.249642)
							(end 0.1778 0.2794)
						)
					)
					(width 0)
					(fill yes)
				)
			)
		)
	)
	(footprint ""
		(layer "B.Cu")
		(at 78.193646 -169.4688 180)
		(property "Reference" "R302"
			(at 0 0 0)
			(layer "B.SilkS")
			(hide yes)
			(effects
				(font
					(size 1.27 1.27)
				)
				(justify mirror)
			)
		)
		(property "Value" "0R2J-2-GP"
			(at -0.064008 -3.993896 180)
			(unlocked yes)
			(layer "B.Fab")
			(hide yes)
			(effects
				(font
					(size 1.016 1.016)
					(thickness 0.1524)
				)
				(justify mirror)
			)
		)
		(property "Device Type" "R402H16"
			(at -0.064008 -5.517896 180)
			(unlocked yes)
			(layer "B.Fab")
			(hide yes)
			(effects
				(font
					(size 1.016 1.016)
					(thickness 0.1524)
				)
				(justify mirror)
			)
		)
		(duplicate_pad_numbers_are_jumpers no)
		(fp_line
			(start 0.508 -0.9398)
			(end 0.508 0.9398)
			(stroke
				(width 0.1524)
				(type default)
			)
			(layer "B.SilkS")
		)
		(fp_line
			(start -0.508 -0.9398)
			(end 0.508 -0.9398)
			(stroke
				(width 0.1524)
				(type default)
			)
			(layer "B.SilkS")
		)
		(fp_rect
			(start 0.508 0.9398)
			(end -0.508 -0.9398)
			(stroke
				(width 0)
				(type default)
			)
			(fill no)
			(layer "B.CrtYd")
		)
		(fp_rect
			(start 0.508 0.9398)
			(end -0.508 -0.9398)
			(stroke
				(width 0)
				(type default)
			)
			(fill no)
			(layer "B.Fab")
		)
		(pad "1" smd custom
			(at 0 -0.4445)
			(size 0.1397 0.1397)
			(layers "B.Cu" "B.Mask" "B.Paste")
			(net "UART_EXP_BMC_TX")
			(options
				(clearance outline)
				(anchor circle)
			)
			(primitives
				(gr_poly
					(pts
						(arc
							(start -0.1778 0.2794)
							(mid -0.249642 0.249642)
							(end -0.2794 0.1778)
						)
						(arc
							(start -0.2794 -0.1778)
							(mid -0.249642 -0.249642)
							(end -0.1778 -0.2794)
						)
						(arc
							(start 0.1778 -0.2794)
							(mid 0.249642 -0.249642)
							(end 0.2794 -0.1778)
						)
						(arc
							(start 0.2794 0.1778)
							(mid 0.249642 0.249642)
							(end 0.1778 0.2794)
						)
					)
					(width 0)
					(fill yes)
				)
			)
		)
		(pad "2" smd custom
			(at 0 0.4445)
			(size 0.1397 0.1397)
			(layers "B.Cu" "B.Mask" "B.Paste")
			(net "UART_EXP_BMC_TX_R")
			(options
				(clearance outline)
				(anchor circle)
			)
			(primitives
				(gr_poly
					(pts
						(arc
							(start -0.1778 0.2794)
							(mid -0.249642 0.249642)
							(end -0.2794 0.1778)
						)
						(arc
							(start -0.2794 -0.1778)
							(mid -0.249642 -0.249642)
							(end -0.1778 -0.2794)
						)
						(arc
							(start 0.1778 -0.2794)
							(mid 0.249642 -0.249642)
							(end 0.2794 -0.1778)
						)
						(arc
							(start 0.2794 0.1778)
							(mid 0.249642 0.249642)
							(end 0.1778 0.2794)
						)
					)
					(width 0)
					(fill yes)
				)
			)
		)
	)
	(footprint ""
		(layer "B.Cu")
		(at 23.58898 -143.81861 180)
		(property "Reference" "C67"
			(at 0 0 0)
			(layer "B.SilkS")
			(hide yes)
			(effects
				(font
					(size 1.27 1.27)
				)
				(justify mirror)
			)
		)
		(property "Value" "SCD1U16V2KX-3GP"
			(at -1.1811 -2.7051 180)
			(unlocked yes)
			(layer "B.Fab")
			(hide yes)
			(effects
				(font
					(size 1.016 1.016)
					(thickness 0.1524)
				)
				(justify mirror)
			)
		)
		(property "Device Type" "C402H22"
			(at -1.1811 -4.2291 180)
			(unlocked yes)
			(layer "B.Fab")
			(hide yes)
			(effects
				(font
					(size 1.016 1.016)
					(thickness 0.1524)
				)
				(justify mirror)
			)
		)
		(duplicate_pad_numbers_are_jumpers no)
		(fp_rect
			(start 0.4318 0.9525)
			(end -0.4318 -0.9525)
			(stroke
				(width 0)
				(type default)
			)
			(fill no)
			(layer "B.CrtYd")
		)
		(fp_rect
			(start 0.4318 0.9525)
			(end -0.4318 -0.9525)
			(stroke
				(width 0)
				(type default)
			)
			(fill no)
			(layer "B.Fab")
		)
		(pad "1" smd custom
			(at 0 -0.4445)
			(size 0.1524 0.1524)
			(layers "B.Cu" "B.Mask" "B.Paste")
			(net "GND")
			(options
				(clearance outline)
				(anchor circle)
			)
			(primitives
				(gr_poly
					(pts
						(arc
							(start 0.3048 0.2032)
							(mid 0.275042 0.275042)
							(end 0.2032 0.3048)
						)
						(arc
							(start -0.2032 0.3048)
							(mid -0.275042 0.275042)
							(end -0.3048 0.2032)
						)
						(arc
							(start -0.3048 -0.2032)
							(mid -0.275042 -0.275042)
							(end -0.2032 -0.3048)
						)
						(arc
							(start 0.2032 -0.3048)
							(mid 0.275042 -0.275042)
							(end 0.3048 -0.2032)
						)
					)
					(width 0)
					(fill yes)
				)
			)
		)
		(pad "2" smd custom
			(at 0 0.4445)
			(size 0.1524 0.1524)
			(layers "B.Cu" "B.Mask" "B.Paste")
			(net "P1V2_STBY")
			(options
				(clearance outline)
				(anchor circle)
			)
			(primitives
				(gr_poly
					(pts
						(arc
							(start 0.3048 0.2032)
							(mid 0.275042 0.275042)
							(end 0.2032 0.3048)
						)
						(arc
							(start -0.2032 0.3048)
							(mid -0.275042 0.275042)
							(end -0.3048 0.2032)
						)
						(arc
							(start -0.3048 -0.2032)
							(mid -0.275042 -0.275042)
							(end -0.2032 -0.3048)
						)
						(arc
							(start 0.2032 -0.3048)
							(mid 0.275042 -0.275042)
							(end 0.3048 -0.2032)
						)
					)
					(width 0)
					(fill yes)
				)
			)
		)
	)
	(footprint ""
		(layer "B.Cu")
		(at 30.549342 -126.760986 180)
		(property "Reference" "R716"
			(at 0 0 0)
			(layer "B.SilkS")
			(hide yes)
			(effects
				(font
					(size 1.27 1.27)
				)
				(justify mirror)
			)
		)
		(property "Value" "10KR2F-2-GP"
			(at -0.064008 -3.993896 180)
			(unlocked yes)
			(layer "B.Fab")
			(hide yes)
			(effects
				(font
					(size 1.016 1.016)
					(thickness 0.1524)
				)
				(justify mirror)
			)
		)
		(property "Device Type" "R402H16"
			(at -0.064008 -5.517896 180)
			(unlocked yes)
			(layer "B.Fab")
			(hide yes)
			(effects
				(font
					(size 1.016 1.016)
					(thickness 0.1524)
				)
				(justify mirror)
			)
		)
		(duplicate_pad_numbers_are_jumpers no)
		(fp_line
			(start 0.508 -0.9398)
			(end 0.508 0.9398)
			(stroke
				(width 0.1524)
				(type default)
			)
			(layer "B.SilkS")
		)
		(fp_line
			(start -0.508 -0.9398)
			(end 0.508 -0.9398)
			(stroke
				(width 0.1524)
				(type default)
			)
			(layer "B.SilkS")
		)
		(fp_rect
			(start 0.508 0.9398)
			(end -0.508 -0.9398)
			(stroke
				(width 0)
				(type default)
			)
			(fill no)
			(layer "B.CrtYd")
		)
		(fp_rect
			(start 0.508 0.9398)
			(end -0.508 -0.9398)
			(stroke
				(width 0)
				(type default)
			)
			(fill no)
			(layer "B.Fab")
		)
		(pad "1" smd custom
			(at 0 -0.4445)
			(size 0.1397 0.1397)
			(layers "B.Cu" "B.Mask" "B.Paste")
			(net "SYS_RESET_N_OUT")
			(options
				(clearance outline)
				(anchor circle)
			)
			(primitives
				(gr_poly
					(pts
						(arc
							(start -0.1778 0.2794)
							(mid -0.249642 0.249642)
							(end -0.2794 0.1778)
						)
						(arc
							(start -0.2794 -0.1778)
							(mid -0.249642 -0.249642)
							(end -0.1778 -0.2794)
						)
						(arc
							(start 0.1778 -0.2794)
							(mid 0.249642 -0.249642)
							(end 0.2794 -0.1778)
						)
						(arc
							(start 0.2794 0.1778)
							(mid 0.249642 0.249642)
							(end 0.1778 0.2794)
						)
					)
					(width 0)
					(fill yes)
				)
			)
		)
		(pad "2" smd custom
			(at 0 0.4445)
			(size 0.1397 0.1397)
			(layers "B.Cu" "B.Mask" "B.Paste")
			(net "GND")
			(options
				(clearance outline)
				(anchor circle)
			)
			(primitives
				(gr_poly
					(pts
						(arc
							(start -0.1778 0.2794)
							(mid -0.249642 0.249642)
							(end -0.2794 0.1778)
						)
						(arc
							(start -0.2794 -0.1778)
							(mid -0.249642 -0.249642)
							(end -0.1778 -0.2794)
						)
						(arc
							(start 0.1778 -0.2794)
							(mid 0.249642 -0.249642)
							(end 0.2794 -0.1778)
						)
						(arc
							(start 0.2794 0.1778)
							(mid 0.249642 0.249642)
							(end 0.1778 0.2794)
						)
					)
					(width 0)
					(fill yes)
				)
			)
		)
	)
)
